# S9S_MB_2U (Grand Teton) — schematic netlist excerpt (pin names and nets, part order shuffled) for the footprints in the layout excerpt that follows; sources: Cadence DE-HDL packaged netlist, KiCad conversion of 03242023_DA0F0TMBIJ0_F0T_Motherboard_J_brd_V01_OCP.brd

R1380  Q_RES  1K 1% CHIP  pkg 0402LF  page 239 : A = P3V3_AUX ; B = JTAG_BMC_DBP_TDO
R2473  Q_RES  49.9 1% CHIP  pkg 0402LF  page 154 : A = FB_BMC_ISOLATE_R1 ; B = FB_BMC_ISOLATE

(kicad_pcb
	(version 20260206)
	(generator "pcbnew")
	(generator_version "10.0")
	(general
		(thickness 1.6)
		(legacy_teardrops no)
	)
	(paper "A4")
	(title_block
		(title "03242023_DA0F0TMBIJ0_F0T_Motherboard_J_brd_V01_OCP.brd")
		(comment 1 "Grand Teton / footprints 1096-1097 of 6105")
	)
	(layers
		(0 "F.Cu" signal "TOP")
		(4 "In1.Cu" signal "GND")
		(6 "In2.Cu" signal "IN1")
		(8 "In3.Cu" signal "GND1")
		(10 "In4.Cu" signal "IN2")
		(12 "In5.Cu" signal "GND2")
		(14 "In6.Cu" signal "IN3")
		(16 "In7.Cu" signal "GND3")
		(18 "In8.Cu" signal "VCC")
		(20 "In9.Cu" signal "VCC1")
		(22 "In10.Cu" signal "GND4")
		(24 "In11.Cu" signal "IN4")
		(26 "In12.Cu" signal "GND5")
		(28 "In13.Cu" signal "IN5")
		(30 "In14.Cu" signal "GND6")
		(32 "In15.Cu" signal "IN6")
		(34 "In16.Cu" signal "GND7")
		(2 "B.Cu" signal "BOTTOM")
		(9 "F.Adhes" user "F.Adhesive")
		(11 "B.Adhes" user "B.Adhesive")
		(13 "F.Paste" user "Package Geometry/Pastemask Top")
		(15 "B.Paste" user "Package Geometry/Pastemask Bottom")
		(5 "F.SilkS" user "Ref Des/Silkscreen Top")
		(7 "B.SilkS" user "Ref Des/Silkscreen Bottom")
		(1 "F.Mask" user "Board Geometry/Soldermask Top")
		(3 "B.Mask" user "Board Geometry/Soldermask Bottom")
		(17 "Dwgs.User" user "User.Drawings")
		(19 "Cmts.User" user "User.Comments")
		(21 "Eco1.User" user "User.Eco1")
		(23 "Eco2.User" user "User.Eco2")
		(25 "Edge.Cuts" user "Board Geometry/Outline")
		(27 "Margin" user)
		(31 "F.CrtYd" user "Package Geometry/Place Bound Top")
		(29 "B.CrtYd" user "Package Geometry/Place Bound Bottom")
		(35 "F.Fab" user "Ref Des/Assembly Top")
		(33 "B.Fab" user "Ref Des/Assembly Bottom")
	)
	(footprint ""
		(layer "F.Cu")
		(at 463.465926 -97.523808)
		(property "Reference" "R2473"
			(at 0 0 0)
			(layer "F.SilkS")
			(hide yes)
			(effects
				(font
					(size 1.27 1.27)
				)
			)
		)
		(property "Value" ""
			(at 0 0 0)
			(layer "F.Fab")
			(effects
				(font
					(size 1.27 1.27)
				)
			)
		)
		(duplicate_pad_numbers_are_jumpers no)
		(fp_line
			(start -0.7874 -0.4064)
			(end 0.7874 -0.4064)
			(stroke
				(width 0.1524)
				(type default)
			)
			(layer "F.SilkS")
		)
		(fp_line
			(start -0.7874 0.4064)
			(end -0.7874 -0.4064)
			(stroke
				(width 0.1524)
				(type default)
			)
			(layer "F.SilkS")
		)
		(fp_line
			(start 0.7874 -0.4064)
			(end 0.7874 0.4064)
			(stroke
				(width 0.1524)
				(type default)
			)
			(layer "F.SilkS")
		)
		(fp_line
			(start 0.7874 0.4064)
			(end -0.7874 0.4064)
			(stroke
				(width 0.1524)
				(type default)
			)
			(layer "F.SilkS")
		)
		(fp_line
			(start -0.67945 -0.305054)
			(end -0.12065 -0.305054)
			(stroke
				(width 0.1)
				(type default)
			)
			(layer "F.Fab")
		)
		(fp_line
			(start -0.67945 0.3048)
			(end -0.67945 -0.305054)
			(stroke
				(width 0.1)
				(type default)
			)
			(layer "F.Fab")
		)
		(fp_line
			(start -0.12065 -0.305054)
			(end -0.12065 -0.2794)
			(stroke
				(width 0.1)
				(type default)
			)
			(layer "F.Fab")
		)
		(fp_line
			(start -0.12065 -0.2794)
			(end 0.12065 -0.2794)
			(stroke
				(width 0.1)
				(type default)
			)
			(layer "F.Fab")
		)
		(fp_line
			(start -0.12065 0.2794)
			(end -0.12065 0.3048)
			(stroke
				(width 0.1)
				(type default)
			)
			(layer "F.Fab")
		)
		(fp_line
			(start -0.12065 0.3048)
			(end -0.67945 0.3048)
			(stroke
				(width 0.1)
				(type default)
			)
			(layer "F.Fab")
		)
		(fp_line
			(start 0.120396 0.2794)
			(end -0.12065 0.2794)
			(stroke
				(width 0.1)
				(type default)
			)
			(layer "F.Fab")
		)
		(fp_line
			(start 0.120396 0.3048)
			(end 0.120396 0.2794)
			(stroke
				(width 0.1)
				(type default)
			)
			(layer "F.Fab")
		)
		(fp_line
			(start 0.12065 -0.3048)
			(end 0.67945 -0.3048)
			(stroke
				(width 0.1)
				(type default)
			)
			(layer "F.Fab")
		)
		(fp_line
			(start 0.12065 -0.2794)
			(end 0.12065 -0.3048)
			(stroke
				(width 0.1)
				(type default)
			)
			(layer "F.Fab")
		)
		(fp_line
			(start 0.67945 -0.3048)
			(end 0.67945 0.3048)
			(stroke
				(width 0.1)
				(type default)
			)
			(layer "F.Fab")
		)
		(fp_line
			(start 0.67945 0.3048)
			(end 0.120396 0.3048)
			(stroke
				(width 0.1)
				(type default)
			)
			(layer "F.Fab")
		)
		(pad "1" smd circle
			(at -0.40005 0)
			(size 0 0)
			(layers "F.Cu" "F.Mask" "F.Paste")
			(net "FB_BMC_ISOLATE_R1")
		)
		(pad "2" smd circle
			(at 0.40005 0)
			(size 0 0)
			(layers "F.Cu" "F.Mask" "F.Paste")
			(net "FB_BMC_ISOLATE")
		)
	)
	(footprint ""
		(layer "F.Cu")
		(at 128.716278 -80.112616)
		(property "Reference" "R1380"
			(at 0 0 0)
			(layer "F.SilkS")
			(hide yes)
			(effects
				(font
					(size 1.27 1.27)
				)
			)
		)
		(property "Value" ""
			(at 0 0 0)
			(layer "F.Fab")
			(effects
				(font
					(size 1.27 1.27)
				)
			)
		)
		(duplicate_pad_numbers_are_jumpers no)
		(fp_line
			(start -0.7874 -0.4064)
			(end 0.7874 -0.4064)
			(stroke
				(width 0.1524)
				(type default)
			)
			(layer "F.SilkS")
		)
		(fp_line
			(start -0.7874 0.4064)
			(end -0.7874 -0.4064)
			(stroke
				(width 0.1524)
				(type default)
			)
			(layer "F.SilkS")
		)
		(fp_line
			(start 0.7874 -0.4064)
			(end 0.7874 0.4064)
			(stroke
				(width 0.1524)
				(type default)
			)
			(layer "F.SilkS")
		)
		(fp_line
			(start 0.7874 0.4064)
			(end -0.7874 0.4064)
			(stroke
				(width 0.1524)
				(type default)
			)
			(layer "F.SilkS")
		)
		(fp_line
			(start -0.67945 -0.305054)
			(end -0.12065 -0.305054)
			(stroke
				(width 0.1)
				(type default)
			)
			(layer "F.Fab")
		)
		(fp_line
			(start -0.67945 0.3048)
			(end -0.67945 -0.305054)
			(stroke
				(width 0.1)
				(type default)
			)
			(layer "F.Fab")
		)
		(fp_line
			(start -0.12065 -0.305054)
			(end -0.12065 -0.2794)
			(stroke
				(width 0.1)
				(type default)
			)
			(layer "F.Fab")
		)
		(fp_line
			(start -0.12065 -0.2794)
			(end 0.12065 -0.2794)
			(stroke
				(width 0.1)
				(type default)
			)
			(layer "F.Fab")
		)
		(fp_line
			(start -0.12065 0.2794)
			(end -0.12065 0.3048)
			(stroke
				(width 0.1)
				(type default)
			)
			(layer "F.Fab")
		)
		(fp_line
			(start -0.12065 0.3048)
			(end -0.67945 0.3048)
			(stroke
				(width 0.1)
				(type default)
			)
			(layer "F.Fab")
		)
		(fp_line
			(start 0.120396 0.2794)
			(end -0.12065 0.2794)
			(stroke
				(width 0.1)
				(type default)
			)
			(layer "F.Fab")
		)
		(fp_line
			(start 0.120396 0.3048)
			(end 0.120396 0.2794)
			(stroke
				(width 0.1)
				(type default)
			)
			(layer "F.Fab")
		)
		(fp_line
			(start 0.12065 -0.3048)
			(end 0.67945 -0.3048)
			(stroke
				(width 0.1)
				(type default)
			)
			(layer "F.Fab")
		)
		(fp_line
			(start 0.12065 -0.2794)
			(end 0.12065 -0.3048)
			(stroke
				(width 0.1)
				(type default)
			)
			(layer "F.Fab")
		)
		(fp_line
			(start 0.67945 -0.3048)
			(end 0.67945 0.3048)
			(stroke
				(width 0.1)
				(type default)
			)
			(layer "F.Fab")
		)
		(fp_line
			(start 0.67945 0.3048)
			(end 0.120396 0.3048)
			(stroke
				(width 0.1)
				(type default)
			)
			(layer "F.Fab")
		)
		(pad "1" smd circle
			(at -0.40005 0)
			(size 0 0)
			(layers "F.Cu" "F.Mask" "F.Paste")
			(net "P3V3_AUX")
		)
		(pad "2" smd circle
			(at 0.40005 0)
			(size 0 0)
			(layers "F.Cu" "F.Mask" "F.Paste")
			(net "JTAG_BMC_DBP_TDO")
		)
	)
)
